(kicad_pcb
	(version 20260206)
	(generator "pcbnew")
	(generator_version "10.0")
	(general
		(thickness 1.6)
		(legacy_teardrops no)
	)
	(paper "A4")
	(title_block
		(title "fcb — Lightning_FCB_BRD.brd")
		(comment 1 "Lightning (Wiwynn / Facebook NVMe JBOF) / footprints 370-375 of 495")
	)
	(layers
		(0 "F.Cu" signal "TOP")
		(4 "In1.Cu" signal "L2GND")
		(6 "In2.Cu" signal "L3VCC")
		(2 "B.Cu" signal "BOTTOM")
		(9 "F.Adhes" user "F.Adhesive")
		(11 "B.Adhes" user "B.Adhesive")
		(13 "F.Paste" user "Package Geometry/Pastemask Top")
		(15 "B.Paste" user "Package Geometry/Pastemask Bottom")
		(5 "F.SilkS" user "Ref Des/Silkscreen Top")
		(7 "B.SilkS" user "Ref Des/Silkscreen Bottom")
		(1 "F.Mask" user "Board Geometry/Soldermask Top")
		(3 "B.Mask" user "Board Geometry/Soldermask Bottom")
		(17 "Dwgs.User" user "User.Drawings")
		(19 "Cmts.User" user "User.Comments")
		(21 "Eco1.User" user "User.Eco1")
		(23 "Eco2.User" user "User.Eco2")
		(25 "Edge.Cuts" user "Board Geometry/Outline")
		(27 "Margin" user)
		(31 "F.CrtYd" user "Package Geometry/Place Bound Top")
		(29 "B.CrtYd" user "Package Geometry/Place Bound Bottom")
		(35 "F.Fab" user "Ref Des/Assembly Top")
		(33 "B.Fab" user "Ref Des/Assembly Bottom")
	)
	(footprint ""
		(layer "F.Cu")
		(at 37.719 -111.633)
		(property "Reference" "PQ8"
			(at 0 0 0)
			(layer "F.SilkS")
			(hide yes)
			(effects
				(font
					(size 1.27 1.27)
				)
			)
		)
		(property "Value" "PH0925CL-GP"
			(at -4.2799 -0.4572 0)
			(unlocked yes)
			(layer "F.Fab")
			(hide yes)
			(effects
				(font
					(size 1.016 1.016)
					(thickness 0.1524)
				)
			)
		)
		(property "Device Type" "LFPAK-5PH48-U"
			(at -4.2799 -1.9812 0)
			(unlocked yes)
			(layer "F.Fab")
			(hide yes)
			(effects
				(font
					(size 1.016 1.016)
					(thickness 0.1524)
				)
			)
		)
		(duplicate_pad_numbers_are_jumpers no)
		(fp_line
			(start -2.7559 -6.5532)
			(end -2.7559 1.0668)
			(stroke
				(width 0.1524)
				(type default)
			)
			(layer "F.SilkS")
		)
		(fp_line
			(start -2.7559 1.0668)
			(end 2.7559 1.0668)
			(stroke
				(width 0.1524)
				(type default)
			)
			(layer "F.SilkS")
		)
		(fp_line
			(start -1.7272 1.1684)
			(end -2.1082 1.1684)
			(stroke
				(width 0.3302)
				(type default)
			)
			(layer "F.SilkS")
		)
		(fp_line
			(start 2.7559 -6.5532)
			(end -2.7559 -6.5532)
			(stroke
				(width 0.1524)
				(type default)
			)
			(layer "F.SilkS")
		)
		(fp_line
			(start 2.7559 1.0668)
			(end 2.7559 -6.5532)
			(stroke
				(width 0.1524)
				(type default)
			)
			(layer "F.SilkS")
		)
		(fp_poly
			(pts
				(xy -2.3368 1.5748) (xy -1.905 1.143) (xy -1.4732 1.5748)
			)
			(stroke
				(width 0)
				(type default)
			)
			(fill yes)
			(layer "F.SilkS")
		)
		(fp_poly
			(pts
				(xy -2.5019 -4.02971) (xy -0.3302 -4.02971) (xy -0.3302 -6.30301) (xy -2.5019 -6.30301)
			)
			(stroke
				(width 0)
				(type default)
			)
			(fill yes)
			(layer "F.Paste")
		)
		(fp_poly
			(pts
				(xy -2.5019 -1.09601) (xy -0.3302 -1.09601) (xy -0.3302 -3.36931) (xy -2.5019 -3.36931)
			)
			(stroke
				(width 0)
				(type default)
			)
			(fill yes)
			(layer "F.Paste")
		)
		(fp_poly
			(pts
				(xy 0.3302 -4.02971) (xy 2.5019 -4.02971) (xy 2.5019 -6.30301) (xy 0.3302 -6.30301)
			)
			(stroke
				(width 0)
				(type default)
			)
			(fill yes)
			(layer "F.Paste")
		)
		(fp_poly
			(pts
				(xy 0.3302 -1.09601) (xy 2.5019 -1.09601) (xy 2.5019 -3.36931) (xy 0.3302 -3.36931)
			)
			(stroke
				(width 0)
				(type default)
			)
			(fill yes)
			(layer "F.Paste")
		)
		(fp_rect
			(start -2.4511 0.3048)
			(end 2.4511 -5.6896)
			(stroke
				(width 0)
				(type default)
			)
			(fill no)
			(layer "F.CrtYd")
		)
		(fp_poly
			(pts
				(xy -3.0099 1.3208) (xy -3.0099 -6.8072) (xy 3.0099 -6.8072) (xy 3.0099 -1.016) (xy 2.4511 -1.016)
				(xy 2.4511 -5.6896) (xy -2.4511 -5.6896) (xy -2.4511 0.3048) (xy 2.4511 0.3048) (xy 2.4511 -1.0033)
				(xy 3.0099 -1.0033) (xy 3.0099 1.3208)
			)
			(stroke
				(width 0)
				(type default)
			)
			(fill no)
			(layer "F.CrtYd")
		)
		(fp_rect
			(start -3.0099 1.3208)
			(end 3.0099 -6.8072)
			(stroke
				(width 0)
				(type default)
			)
			(fill no)
			(layer "F.Fab")
		)
		(pad "1" smd rect
			(at -1.905 0)
			(size 0.762 1.6256)
			(layers "F.Cu" "F.Mask" "F.Paste")
			(net "P12VL")
		)
		(pad "2" smd rect
			(at -0.635 0)
			(size 0.762 1.6256)
			(layers "F.Cu" "F.Mask" "F.Paste")
			(net "P12VL")
		)
		(pad "3" smd rect
			(at 0.635 0)
			(size 0.762 1.6256)
			(layers "F.Cu" "F.Mask" "F.Paste")
			(net "P12VL")
		)
		(pad "4" smd rect
			(at 1.905 0)
			(size 0.762 1.6256)
			(layers "F.Cu" "F.Mask" "F.Paste")
			(net "P12VL_2490_GATE_DRV")
		)
		(pad "5" smd rect
			(at 0 -3.69951)
			(size 5.0038 5.207)
			(layers "F.Cu" "F.Mask" "F.Paste")
			(net "P12VL_NET")
		)
	)
	(footprint ""
		(layer "F.Cu")
		(at 15.494 -168.2242 90)
		(property "Reference" "C34"
			(at 0 0 90)
			(layer "F.SilkS")
			(hide yes)
			(effects
				(font
					(size 1.27 1.27)
				)
			)
		)
		(property "Value" "SC1U25V3KX-1-GP"
			(at 0 -2.8194 90)
			(unlocked yes)
			(layer "F.Fab")
			(hide yes)
			(effects
				(font
					(size 1.016 1.016)
					(thickness 0.1524)
				)
			)
		)
		(property "Device Type" "C603H36"
			(at 0 -4.3434 90)
			(unlocked yes)
			(layer "F.Fab")
			(hide yes)
			(effects
				(font
					(size 1.016 1.016)
					(thickness 0.1524)
				)
			)
		)
		(duplicate_pad_numbers_are_jumpers no)
		(fp_line
			(start 0.508 0)
			(end -0.508 0)
			(stroke
				(width 0.2032)
				(type default)
			)
			(layer "F.SilkS")
		)
		(fp_rect
			(start -0.5842 1.3335)
			(end 0.5842 -1.3335)
			(stroke
				(width 0)
				(type default)
			)
			(fill no)
			(layer "F.CrtYd")
		)
		(fp_rect
			(start -0.5842 1.3335)
			(end 0.5842 -1.3335)
			(stroke
				(width 0)
				(type default)
			)
			(fill no)
			(layer "F.Fab")
		)
		(pad "1" smd custom
			(at 0 -0.762 90)
			(size 0.2159 0.2159)
			(layers "F.Cu" "F.Mask" "F.Paste")
			(net "P12V")
			(options
				(clearance outline)
				(anchor circle)
			)
			(primitives
				(gr_poly
					(pts
						(arc
							(start -0.3302 -0.4318)
							(mid -0.402042 -0.402042)
							(end -0.4318 -0.3302)
						)
						(arc
							(start -0.4318 0.3302)
							(mid -0.402042 0.402042)
							(end -0.3302 0.4318)
						)
						(arc
							(start 0.3302 0.4318)
							(mid 0.402042 0.402042)
							(end 0.4318 0.3302)
						)
						(arc
							(start 0.4318 -0.3302)
							(mid 0.402042 -0.402042)
							(end 0.3302 -0.4318)
						)
					)
					(width 0)
					(fill yes)
				)
			)
		)
		(pad "2" smd custom
			(at 0 0.762 90)
			(size 0.2159 0.2159)
			(layers "F.Cu" "F.Mask" "F.Paste")
			(net "GND")
			(options
				(clearance outline)
				(anchor circle)
			)
			(primitives
				(gr_poly
					(pts
						(arc
							(start -0.3302 -0.4318)
							(mid -0.402042 -0.402042)
							(end -0.4318 -0.3302)
						)
						(arc
							(start -0.4318 0.3302)
							(mid -0.402042 0.402042)
							(end -0.3302 0.4318)
						)
						(arc
							(start 0.3302 0.4318)
							(mid 0.402042 0.402042)
							(end 0.4318 0.3302)
						)
						(arc
							(start 0.4318 -0.3302)
							(mid 0.402042 -0.402042)
							(end 0.3302 -0.4318)
						)
					)
					(width 0)
					(fill yes)
				)
			)
		)
	)
	(footprint ""
		(layer "F.Cu")
		(at 18.3388 -179.8828 180)
		(property "Reference" "C55"
			(at 0 0 180)
			(layer "F.SilkS")
			(hide yes)
			(effects
				(font
					(size 1.27 1.27)
				)
			)
		)
		(property "Value" "SC1U16V3KX-5GP"
			(at 0 -2.8194 180)
			(unlocked yes)
			(layer "F.Fab")
			(hide yes)
			(effects
				(font
					(size 1.016 1.016)
					(thickness 0.1524)
				)
			)
		)
		(property "Device Type" "C603H36"
			(at 0 -4.3434 180)
			(unlocked yes)
			(layer "F.Fab")
			(hide yes)
			(effects
				(font
					(size 1.016 1.016)
					(thickness 0.1524)
				)
			)
		)
		(duplicate_pad_numbers_are_jumpers no)
		(fp_line
			(start 0.508 0)
			(end -0.508 0)
			(stroke
				(width 0.2032)
				(type default)
			)
			(layer "F.SilkS")
		)
		(fp_rect
			(start -0.5842 1.3335)
			(end 0.5842 -1.3335)
			(stroke
				(width 0)
				(type default)
			)
			(fill no)
			(layer "F.CrtYd")
		)
		(fp_rect
			(start -0.5842 1.3335)
			(end 0.5842 -1.3335)
			(stroke
				(width 0)
				(type default)
			)
			(fill no)
			(layer "F.Fab")
		)
		(pad "1" smd custom
			(at 0 -0.762 180)
			(size 0.2159 0.2159)
			(layers "F.Cu" "F.Mask" "F.Paste")
			(net "P3V3")
			(options
				(clearance outline)
				(anchor circle)
			)
			(primitives
				(gr_poly
					(pts
						(arc
							(start -0.3302 -0.4318)
							(mid -0.402042 -0.402042)
							(end -0.4318 -0.3302)
						)
						(arc
							(start -0.4318 0.3302)
							(mid -0.402042 0.402042)
							(end -0.3302 0.4318)
						)
						(arc
							(start 0.3302 0.4318)
							(mid 0.402042 0.402042)
							(end 0.4318 0.3302)
						)
						(arc
							(start 0.4318 -0.3302)
							(mid 0.402042 -0.402042)
							(end 0.3302 -0.4318)
						)
					)
					(width 0)
					(fill yes)
				)
			)
		)
		(pad "2" smd custom
			(at 0 0.762 180)
			(size 0.2159 0.2159)
			(layers "F.Cu" "F.Mask" "F.Paste")
			(net "GND")
			(options
				(clearance outline)
				(anchor circle)
			)
			(primitives
				(gr_poly
					(pts
						(arc
							(start -0.3302 -0.4318)
							(mid -0.402042 -0.402042)
							(end -0.4318 -0.3302)
						)
						(arc
							(start -0.4318 0.3302)
							(mid -0.402042 0.402042)
							(end -0.3302 0.4318)
						)
						(arc
							(start 0.3302 0.4318)
							(mid 0.402042 0.402042)
							(end 0.4318 0.3302)
						)
						(arc
							(start 0.4318 -0.3302)
							(mid 0.402042 -0.402042)
							(end 0.3302 -0.4318)
						)
					)
					(width 0)
					(fill yes)
				)
			)
		)
	)
	(footprint ""
		(layer "F.Cu")
		(at 18.669 -410.591)
		(property "Reference" "PR29"
			(at 0 0 0)
			(layer "F.SilkS")
			(hide yes)
			(effects
				(font
					(size 1.27 1.27)
				)
			)
		)
		(property "Value" "D0005RL1632F-GP-U"
			(at 3.2258 1.2954 0)
			(unlocked yes)
			(layer "F.Fab")
			(hide yes)
			(effects
				(font
					(size 1.016 1.016)
					(thickness 0.1524)
				)
			)
		)
		(property "Device Type" "RL3115-4PH45"
			(at 3.2258 -0.2286 0)
			(unlocked yes)
			(layer "F.Fab")
			(hide yes)
			(effects
				(font
					(size 1.016 1.016)
					(thickness 0.1524)
				)
			)
		)
		(duplicate_pad_numbers_are_jumpers no)
		(fp_line
			(start -2.0574 -1.7653)
			(end -2.0574 -0.4064)
			(stroke
				(width 0.3302)
				(type default)
			)
			(layer "F.SilkS")
		)
		(fp_line
			(start -1.9685 -1.651)
			(end 1.9685 -1.651)
			(stroke
				(width 0.1524)
				(type default)
			)
			(layer "F.SilkS")
		)
		(fp_line
			(start -1.9685 1.651)
			(end -1.9685 -1.651)
			(stroke
				(width 0.1524)
				(type default)
			)
			(layer "F.SilkS")
		)
		(fp_line
			(start -0.5334 -1.7653)
			(end -2.0574 -1.7653)
			(stroke
				(width 0.3302)
				(type default)
			)
			(layer "F.SilkS")
		)
		(fp_line
			(start 1.9685 -1.651)
			(end 1.9685 1.651)
			(stroke
				(width 0.1524)
				(type default)
			)
			(layer "F.SilkS")
		)
		(fp_line
			(start 1.9685 1.651)
			(end -1.9685 1.651)
			(stroke
				(width 0.1524)
				(type default)
			)
			(layer "F.SilkS")
		)
		(fp_poly
			(pts
				(xy -0.561594 -1.726946) (xy -0.053594 -2.234946) (xy -1.069594 -2.234946)
			)
			(stroke
				(width 0)
				(type default)
			)
			(fill yes)
			(layer "F.SilkS")
		)
		(fp_rect
			(start -1.524 0.7493)
			(end 1.524 -0.7493)
			(stroke
				(width 0)
				(type default)
			)
			(fill no)
			(layer "F.CrtYd")
		)
		(fp_poly
			(pts
				(xy -2.2225 1.905) (xy -2.2225 -1.905) (xy 2.2225 -1.905) (xy 2.2225 -0.7493) (xy -1.524 -0.7493)
				(xy -1.524 0.7493) (xy 1.524 0.7493) (xy 1.524 -0.7366) (xy 2.2225 -0.7366) (xy 2.2225 1.905)
			)
			(stroke
				(width 0)
				(type default)
			)
			(fill no)
			(layer "F.CrtYd")
		)
		(fp_rect
			(start -2.2225 1.905)
			(end 2.2225 -1.905)
			(stroke
				(width 0)
				(type default)
			)
			(fill no)
			(layer "F.Fab")
		)
		(pad "1" smd rect
			(at -0.5715 -0.813562)
			(size 2.286 1.143)
			(layers "F.Cu" "F.Mask" "F.Paste")
			(net "P12V_AUX")
		)
		(pad "2" smd rect
			(at -0.5715 0.813562)
			(size 2.286 1.143)
			(layers "F.Cu" "F.Mask" "F.Paste")
			(net "P12V_SENSE_TRACE")
		)
		(pad "3" smd rect
			(at 1.334008 -0.813562)
			(size 0.762 1.143)
			(layers "F.Cu" "F.Mask" "F.Paste")
			(net "SENSE+_R1")
		)
		(pad "4" smd rect
			(at 1.334008 0.813562)
			(size 0.762 1.143)
			(layers "F.Cu" "F.Mask" "F.Paste")
			(net "SENSE-_R1")
		)
		(zone
			(layer "F.Cu")
			(hatch none 0.5)
			(connect_pads
				(clearance 0)
			)
			(min_thickness 0.25)
			(keepout
				(tracks allowed)
				(vias not_allowed)
				(pads allowed)
				(copperpour not_allowed)
				(footprints allowed)
			)
			(placement
				(enabled no)
				(sheetname "")
			)
			(fill
				(thermal_gap 0.5)
				(thermal_bridge_width 0.5)
				(island_removal_mode 0)
			)
			(polygon
				(pts
					(xy 19.2405 -410.833062) (xy 19.622008 -410.833062) (xy 19.622008 -411.3403) (xy 19.2405 -411.3403)
				)
			)
		)
		(zone
			(layer "F.Cu")
			(hatch none 0.5)
			(connect_pads
				(clearance 0)
			)
			(min_thickness 0.25)
			(keepout
				(tracks not_allowed)
				(vias allowed)
				(pads allowed)
				(copperpour not_allowed)
				(footprints allowed)
			)
			(placement
				(enabled no)
				(sheetname "")
			)
			(fill
				(thermal_gap 0.5)
				(thermal_bridge_width 0.5)
				(island_removal_mode 0)
			)
			(polygon
				(pts
					(xy 19.2405 -410.833062) (xy 19.622008 -410.833062) (xy 19.622008 -411.3403) (xy 19.2405 -411.3403)
				)
			)
		)
		(zone
			(layer "F.Cu")
			(hatch none 0.5)
			(connect_pads
				(clearance 0)
			)
			(min_thickness 0.25)
			(keepout
				(tracks not_allowed)
				(vias allowed)
				(pads allowed)
				(copperpour not_allowed)
				(footprints allowed)
			)
			(placement
				(enabled no)
				(sheetname "")
			)
			(fill
				(thermal_gap 0.5)
				(thermal_bridge_width 0.5)
				(island_removal_mode 0)
			)
			(polygon
				(pts
					(xy 19.2405 -409.8417) (xy 19.622008 -409.8417) (xy 19.622008 -410.348938) (xy 19.2405 -410.348938)
				)
			)
		)
		(zone
			(layer "F.Cu")
			(hatch none 0.5)
			(connect_pads
				(clearance 0)
			)
			(min_thickness 0.25)
			(keepout
				(tracks allowed)
				(vias not_allowed)
				(pads allowed)
				(copperpour not_allowed)
				(footprints allowed)
			)
			(placement
				(enabled no)
				(sheetname "")
			)
			(fill
				(thermal_gap 0.5)
				(thermal_bridge_width 0.5)
				(island_removal_mode 0)
			)
			(polygon
				(pts
					(xy 19.2405 -409.8417) (xy 19.622008 -409.8417) (xy 19.622008 -410.348938) (xy 19.2405 -410.348938)
				)
			)
		)
	)
	(footprint ""
		(layer "F.Cu")
		(at 39.123366 -156.22651 90)
		(property "Reference" "R6"
			(at 0 0 90)
			(layer "F.SilkS")
			(hide yes)
			(effects
				(font
					(size 1.27 1.27)
				)
			)
		)
		(property "Value" "0R2J-2-GP"
			(at 0.064008 -3.993896 90)
			(unlocked yes)
			(layer "F.Fab")
			(hide yes)
			(effects
				(font
					(size 1.016 1.016)
					(thickness 0.1524)
				)
			)
		)
		(property "Device Type" "R402H16"
			(at 0.064008 -5.517896 90)
			(unlocked yes)
			(layer "F.Fab")
			(hide yes)
			(effects
				(font
					(size 1.016 1.016)
					(thickness 0.1524)
				)
			)
		)
		(duplicate_pad_numbers_are_jumpers no)
		(fp_line
			(start 0.508 -0.9398)
			(end -0.508 -0.9398)
			(stroke
				(width 0.1524)
				(type default)
			)
			(layer "F.SilkS")
		)
		(fp_line
			(start -0.508 -0.9398)
			(end -0.508 0.9398)
			(stroke
				(width 0.1524)
				(type default)
			)
			(layer "F.SilkS")
		)
		(fp_rect
			(start -0.508 0.9398)
			(end 0.508 -0.9398)
			(stroke
				(width 0)
				(type default)
			)
			(fill no)
			(layer "F.CrtYd")
		)
		(fp_rect
			(start -0.508 0.9398)
			(end 0.508 -0.9398)
			(stroke
				(width 0)
				(type default)
			)
			(fill no)
			(layer "F.Fab")
		)
		(pad "1" smd custom
			(at 0 -0.4445 90)
			(size 0.1397 0.1397)
			(layers "F.Cu" "F.Mask" "F.Paste")
			(net "NCT7904_SMI")
			(options
				(clearance outline)
				(anchor circle)
			)
			(primitives
				(gr_poly
					(pts
						(arc
							(start -0.1778 -0.2794)
							(mid -0.249642 -0.249642)
							(end -0.2794 -0.1778)
						)
						(arc
							(start -0.2794 0.1778)
							(mid -0.249642 0.249642)
							(end -0.1778 0.2794)
						)
						(arc
							(start 0.1778 0.2794)
							(mid 0.249642 0.249642)
							(end 0.2794 0.1778)
						)
						(arc
							(start 0.2794 -0.1778)
							(mid 0.249642 -0.249642)
							(end 0.1778 -0.2794)
						)
					)
					(width 0)
					(fill yes)
				)
			)
		)
		(pad "2" smd custom
			(at 0 0.4445 90)
			(size 0.1397 0.1397)
			(layers "F.Cu" "F.Mask" "F.Paste")
			(net "TEMP_ALM#")
			(options
				(clearance outline)
				(anchor circle)
			)
			(primitives
				(gr_poly
					(pts
						(arc
							(start -0.1778 -0.2794)
							(mid -0.249642 -0.249642)
							(end -0.2794 -0.1778)
						)
						(arc
							(start -0.2794 0.1778)
							(mid -0.249642 0.249642)
							(end -0.1778 0.2794)
						)
						(arc
							(start 0.1778 0.2794)
							(mid 0.249642 0.249642)
							(end 0.2794 0.1778)
						)
						(arc
							(start 0.2794 -0.1778)
							(mid 0.249642 -0.249642)
							(end 0.1778 -0.2794)
						)
					)
					(width 0)
					(fill yes)
				)
			)
		)
	)
	(footprint ""
		(layer "F.Cu")
		(at 40.513 -252.984)
		(property "Reference" "R129"
			(at 0 0 0)
			(layer "F.SilkS")
			(hide yes)
			(effects
				(font
					(size 1.27 1.27)
				)
			)
		)
		(property "Value" "330R2J-3-GP"
			(at 0.064008 -3.993896 0)
			(unlocked yes)
			(layer "F.Fab")
			(hide yes)
			(effects
				(font
					(size 1.016 1.016)
					(thickness 0.1524)
				)
			)
		)
		(property "Device Type" "R402H16"
			(at 0.064008 -5.517896 0)
			(unlocked yes)
			(layer "F.Fab")
			(hide yes)
			(effects
				(font
					(size 1.016 1.016)
					(thickness 0.1524)
				)
			)
		)
		(duplicate_pad_numbers_are_jumpers no)
		(fp_line
			(start -0.508 -0.9398)
			(end -0.508 0.9398)
			(stroke
				(width 0.1524)
				(type default)
			)
			(layer "F.SilkS")
		)
		(fp_line
			(start 0.508 -0.9398)
			(end -0.508 -0.9398)
			(stroke
				(width 0.1524)
				(type default)
			)
			(layer "F.SilkS")
		)
		(fp_rect
			(start -0.508 0.9398)
			(end 0.508 -0.9398)
			(stroke
				(width 0)
				(type default)
			)
			(fill no)
			(layer "F.CrtYd")
		)
		(fp_rect
			(start -0.508 0.9398)
			(end 0.508 -0.9398)
			(stroke
				(width 0)
				(type default)
			)
			(fill no)
			(layer "F.Fab")
		)
		(pad "1" smd custom
			(at 0 -0.4445)
			(size 0.1397 0.1397)
			(layers "F.Cu" "F.Mask" "F.Paste")
			(net "P3V3")
			(options
				(clearance outline)
				(anchor circle)
			)
			(primitives
				(gr_poly
					(pts
						(arc
							(start -0.1778 -0.2794)
							(mid -0.249642 -0.249642)
							(end -0.2794 -0.1778)
						)
						(arc
							(start -0.2794 0.1778)
							(mid -0.249642 0.249642)
							(end -0.1778 0.2794)
						)
						(arc
							(start 0.1778 0.2794)
							(mid 0.249642 0.249642)
							(end 0.2794 0.1778)
						)
						(arc
							(start 0.2794 -0.1778)
							(mid 0.249642 -0.249642)
							(end 0.1778 -0.2794)
						)
					)
					(width 0)
					(fill yes)
				)
			)
		)
		(pad "2" smd custom
			(at 0 0.4445)
			(size 0.1397 0.1397)
			(layers "F.Cu" "F.Mask" "F.Paste")
			(net "LED_DR_LED5")
			(options
				(clearance outline)
				(anchor circle)
			)
			(primitives
				(gr_poly
					(pts
						(arc
							(start -0.1778 -0.2794)
							(mid -0.249642 -0.249642)
							(end -0.2794 -0.1778)
						)
						(arc
							(start -0.2794 0.1778)
							(mid -0.249642 0.249642)
							(end -0.1778 0.2794)
						)
						(arc
							(start 0.1778 0.2794)
							(mid 0.249642 0.249642)
							(end 0.2794 0.1778)
						)
						(arc
							(start 0.2794 -0.1778)
							(mid 0.249642 -0.249642)
							(end 0.1778 -0.2794)
						)
					)
					(width 0)
					(fill yes)
				)
			)
		)
	)
)
